#ISCELL
  mstr_misc dns *
  *
#ISCELL
  mstr_symbols design_note *
  *
#ISCELL
  mstr_symbols intel_corp_bpage *
  *
#CELL
  mstr_clock nb3w1200l *
  page102_i1
#CELL
  mstr_discrete cap *
  page102_i10
#CELL
  dev_discrete cap_a *
  page102_i11
#CELL
  dev_discrete cap_a *
  page102_i12
#CELL
  dev_discrete cap_a *
  page102_i13
#CELL
  dev_discrete cap_a *
  page102_i14
#CELL
  dev_discrete cap_a *
  page102_i15
#CELL
  dev_discrete cap_a *
  page102_i16
#ISCELL
  mstr_symbols gnd *
  page102_i17
#CELL
  dev_discrete cap_a *
  page102_i18
#CELL
  dev_discrete cap_a *
  page102_i19
#CELL
  mstr_discrete res *
  page102_i21
#ISCELL
  mstr_symbols gnd *
  page102_i22
#ISCELL
  mstr_symbols vcc_core *
  page102_i23
#ISCELL
  mstr_symbols vcc_core *
  page102_i24
#ISCELL
  mstr_symbols vcc_core *
  page102_i25
#CELL
  mstr_discrete res *
  page102_i26
#ISCELL
  mstr_symbols vcc_core *
  page102_i27
#CELL
  dev_discrete cap_a *
  page102_i28
#ISCELL
  mstr_symbols gnd *
  page102_i29
#CELL
  dev_discrete cap_a *
  page102_i30
#ISCELL
  mstr_standard offpage *
  page102_i31
#ISCELL
  mstr_standard offpage *
  page102_i32
#ISCELL
  mstr_standard offpage *
  page102_i33
#ISCELL
  mstr_standard offpage *
  page102_i34
#ISCELL
  mstr_standard offpage *
  page102_i35
#ISCELL
  mstr_standard offpage *
  page102_i36
#CELL
  mstr_discrete res *
  page102_i37
#CELL
  mstr_discrete res *
  page102_i38
#ISCELL
  mstr_standard offpage *
  page102_i4
#ISCELL
  mstr_standard offpage *
  page102_i41
#ISCELL
  mstr_standard offpage *
  page102_i42
#ISCELL
  mstr_symbols vcc_core *
  page102_i43
#ISCELL
  mstr_symbols gnd *
  page102_i44
#CELL
  mstr_discrete res *
  page102_i45
#CELL
  mstr_discrete res *
  page102_i46
#CELL
  mstr_discrete res *
  page102_i47
#ISCELL
  mstr_symbols vcc_core *
  page102_i49
#ISCELL
  mstr_standard offpage *
  page102_i5
#ISCELL
  mstr_symbols gnd *
  page102_i50
#ISCELL
  mstr_standard offpage *
  page102_i51
#ISCELL
  mstr_standard offpage *
  page102_i52
#CELL
  mstr_discrete res *
  page102_i53
#ISCELL
  mstr_standard offpage *
  page102_i54
#ISCELL
  mstr_standard offpage *
  page102_i55
#ISCELL
  mstr_standard offpage *
  page102_i56
#ISCELL
  mstr_standard offpage *
  page102_i57
#ISCELL
  mstr_standard offpage *
  page102_i58
#ISCELL
  mstr_standard offpage *
  page102_i59
#ISCELL
  mstr_symbols gnd *
  page102_i6
#ISCELL
  mstr_standard offpage *
  page102_i60
#ISCELL
  mstr_standard offpage *
  page102_i61
#ISCELL
  mstr_standard offpage *
  page102_i62
#ISCELL
  mstr_standard offpage *
  page102_i63
#ISCELL
  mstr_standard offpage *
  page102_i64
#ISCELL
  mstr_standard offpage *
  page102_i65
#ISCELL
  mstr_standard offpage *
  page102_i66
#ISCELL
  mstr_standard offpage *
  page102_i67
#ISCELL
  mstr_standard offpage *
  page102_i68
#ISCELL
  mstr_standard offpage *
  page102_i69
#ISCELL
  mstr_standard offpage *
  page102_i7
#ISCELL
  mstr_standard offpage *
  page102_i70
#ISCELL
  mstr_standard offpage *
  page102_i71
#ISCELL
  mstr_standard offpage *
  page102_i72
#ISCELL
  mstr_standard offpage *
  page102_i73
#ISCELL
  mstr_standard offpage *
  page102_i74
#ISCELL
  mstr_standard offpage *
  page102_i75
#ISCELL
  mstr_standard offpage *
  page102_i76
#ISCELL
  mstr_standard offpage *
  page102_i77
#CELL
  dev_discrete cap_a *
  page102_i79
#CELL
  mstr_discrete ferrite *
  page102_i8
#CELL
  mstr_discrete res *
  page102_i80
#CELL
  mstr_discrete res *
  page102_i81
#CELL
  mstr_discrete res *
  page102_i82
#ISCELL
  mstr_standard offpage *
  page102_i83
#ISCELL
  mstr_standard offpage *
  page102_i84
#ISCELL
  mstr_standard offpage *
  page102_i85
#ISCELL
  mstr_standard offpage *
  page102_i86
#CELL
  mstr_discrete res *
  page102_i87
#ISCELL
  mstr_standard offpage *
  page102_i89
#ISCELL
  mstr_symbols p3v3 *
  page102_i9
#ISCELL
  mstr_standard offpage *
  page102_i90
#CELL
  mstr_discrete res *
  page102_i91
#CELL
  mstr_discrete res *
  page102_i93
#CELL
  mstr_discrete res *
  page102_i94
#ISCELL
  mstr_symbols p3v3 *
  page102_i95
#ISCELL
  mstr_standard offpage *
  page102_i96
#ISCELL
  mstr_standard offpage *
  page102_i97
#ISCELL
  mstr_standard offpage *
  page102_i98
#ISCELL
  mstr_standard offpage *
  page102_i99
